(kicad_pcb
	(version 20241229)
	(generator "pcbnew")
	(generator_version "9.0")
	(general
		(thickness 1.599998)
		(legacy_teardrops no)
	)
	(paper "A4")
	(title_block
		(title "Artix - Datacenter Secure Control Module (DC-SCM)")
		(date "2024-11-06")
		(rev "1.1.3")
		(comment 9 "footprints 219-222 of 544")
	)
	(layers
		(0 "F.Cu" signal)
		(4 "In1.Cu" signal)
		(6 "In2.Cu" signal)
		(8 "In3.Cu" signal)
		(10 "In4.Cu" signal)
		(12 "In5.Cu" signal)
		(14 "In6.Cu" signal)
		(2 "B.Cu" signal)
		(9 "F.Adhes" user "F.Adhesive")
		(11 "B.Adhes" user "B.Adhesive")
		(13 "F.Paste" user)
		(15 "B.Paste" user)
		(5 "F.SilkS" user "F.Silkscreen")
		(7 "B.SilkS" user "B.Silkscreen")
		(1 "F.Mask" user)
		(3 "B.Mask" user)
		(17 "Dwgs.User" user "User.Drawings")
		(19 "Cmts.User" user "User.Comments")
		(21 "Eco1.User" user "User.Eco1")
		(23 "Eco2.User" user "User.Eco2")
		(25 "Edge.Cuts" user)
		(27 "Margin" user)
		(31 "F.CrtYd" user "F.Courtyard")
		(29 "B.CrtYd" user "B.Courtyard")
		(35 "F.Fab" user)
		(33 "B.Fab" user)
	)
	(footprint "antmicro-footprints:C_0402_1005Metric"
		(layer "F.Cu")
		(at 133.005 168.181 -90)
		(descr "Capacitor SMD 0402")
		(tags "capacitor SMD 0402")
		(property "Reference" "C182"
			(at 0.819 -0.404 90)
			(layer "F.SilkS")
			(effects
				(font
					(size 0.7 0.7)
					(thickness 0.15)
				)
				(justify right bottom)
			)
		)
		(property "Value" "C_100n_6V3_0402"
			(at 0 1.4 90)
			(layer "F.Fab")
			(effects
				(font
					(size 0.7 0.7)
					(thickness 0.15)
				)
				(justify right bottom)
			)
		)
		(property "Datasheet" "https://www.passivecomponent.com/wp-content/uploads/datasheet/WTC_MLCC_General_Purpose.pdf"
			(at 0 0 270)
			(layer "F.Fab")
			(hide yes)
			(effects
				(font
					(size 1.27 1.27)
					(thickness 0.15)
				)
			)
		)
		(property "Description" "SMT Multilayer Ceramic Capacitor, 0.1 µF, 6.3 V, 0402 [1005 Metric], ± 10%, X5R, Walsin MLCC"
			(at 0 0 270)
			(layer "F.Fab")
			(hide yes)
			(effects
				(font
					(size 1.27 1.27)
					(thickness 0.15)
				)
			)
		)
		(property "Author" "Antmicro"
			(at -35.176 301.186 0)
			(layer "F.Fab")
			(hide yes)
			(effects
				(font
					(size 1 1)
					(thickness 0.15)
				)
			)
		)
		(property "Dielectric" ""
			(at -35.176 301.186 0)
			(layer "F.Fab")
			(hide yes)
			(effects
				(font
					(size 1 1)
					(thickness 0.15)
				)
			)
		)
		(property "License" "Apache-2.0"
			(at -35.176 301.186 0)
			(layer "F.Fab")
			(hide yes)
			(effects
				(font
					(size 1 1)
					(thickness 0.15)
				)
			)
		)
		(property "MPN" "0402X104K6R3CT"
			(at -35.176 301.186 0)
			(layer "F.Fab")
			(hide yes)
			(effects
				(font
					(size 1 1)
					(thickness 0.15)
				)
			)
		)
		(property "Manufacturer" "Walsin"
			(at -35.176 301.186 0)
			(layer "F.Fab")
			(hide yes)
			(effects
				(font
					(size 1 1)
					(thickness 0.15)
				)
			)
		)
		(property "Public" "False"
			(at -35.176 301.186 0)
			(layer "F.Fab")
			(hide yes)
			(effects
				(font
					(size 1 1)
					(thickness 0.15)
				)
			)
		)
		(property "Val" "100n"
			(at -35.176 301.186 0)
			(layer "F.Fab")
			(hide yes)
			(effects
				(font
					(size 1 1)
					(thickness 0.15)
				)
			)
		)
		(property "Voltage" ""
			(at -35.176 301.186 0)
			(layer "F.Fab")
			(hide yes)
			(effects
				(font
					(size 1 1)
					(thickness 0.15)
				)
			)
		)
		(sheetname "/PCIe-connector/")
		(sheetfile "pcie-conn.kicad_sch")
		(attr smd)
		(fp_rect
			(start -0.925 -0.47)
			(end 0.925 0.47)
			(stroke
				(width 0.05)
				(type default)
			)
			(fill no)
			(layer "F.CrtYd")
		)
		(fp_line
			(start -0.494 0.248)
			(end -0.494 -0.25)
			(stroke
				(width 0.15)
				(type solid)
			)
			(layer "F.Fab")
		)
		(fp_line
			(start 0.504 0.248)
			(end -0.494 0.248)
			(stroke
				(width 0.15)
				(type solid)
			)
			(layer "F.Fab")
		)
		(fp_line
			(start -0.494 -0.25)
			(end 0.504 -0.25)
			(stroke
				(width 0.15)
				(type solid)
			)
			(layer "F.Fab")
		)
		(fp_line
			(start 0.504 -0.25)
			(end 0.504 0.248)
			(stroke
				(width 0.15)
				(type solid)
			)
			(layer "F.Fab")
		)
		(pad "1" smd roundrect
			(at -0.48 0 270)
			(size 0.59 0.64)
			(layers "F.Cu" "F.Mask" "F.Paste")
			(roundrect_rratio 0.25)
			(net 376 "/PCIe-connector/PCIE_HPM_TX3_C_N")
			(pintype "passive")
		)
		(pad "2" smd roundrect
			(at 0.48 0 270)
			(size 0.59 0.64)
			(layers "F.Cu" "F.Mask" "F.Paste")
			(roundrect_rratio 0.25)
			(net 358 "PCIE_HPM_TX[3]_N")
			(pintype "passive")
		)
	)
	(footprint "antmicro-footprints:C_0402_1005Metric"
		(layer "F.Cu")
		(at 131.995 168.181 -90)
		(descr "Capacitor SMD 0402")
		(tags "capacitor SMD 0402")
		(property "Reference" "C180"
			(at 0.819 -0.404 90)
			(layer "F.SilkS")
			(effects
				(font
					(size 0.7 0.7)
					(thickness 0.15)
				)
				(justify right bottom)
			)
		)
		(property "Value" "C_100n_6V3_0402"
			(at 0 1.4 90)
			(layer "F.Fab")
			(effects
				(font
					(size 0.7 0.7)
					(thickness 0.15)
				)
				(justify right bottom)
			)
		)
		(property "Datasheet" "https://www.passivecomponent.com/wp-content/uploads/datasheet/WTC_MLCC_General_Purpose.pdf"
			(at 0 0 270)
			(layer "F.Fab")
			(hide yes)
			(effects
				(font
					(size 1.27 1.27)
					(thickness 0.15)
				)
			)
		)
		(property "Description" "SMT Multilayer Ceramic Capacitor, 0.1 µF, 6.3 V, 0402 [1005 Metric], ± 10%, X5R, Walsin MLCC"
			(at 0 0 270)
			(layer "F.Fab")
			(hide yes)
			(effects
				(font
					(size 1.27 1.27)
					(thickness 0.15)
				)
			)
		)
		(property "Author" "Antmicro"
			(at -36.186 300.176 0)
			(layer "F.Fab")
			(hide yes)
			(effects
				(font
					(size 1 1)
					(thickness 0.15)
				)
			)
		)
		(property "Dielectric" ""
			(at -36.186 300.176 0)
			(layer "F.Fab")
			(hide yes)
			(effects
				(font
					(size 1 1)
					(thickness 0.15)
				)
			)
		)
		(property "License" "Apache-2.0"
			(at -36.186 300.176 0)
			(layer "F.Fab")
			(hide yes)
			(effects
				(font
					(size 1 1)
					(thickness 0.15)
				)
			)
		)
		(property "MPN" "0402X104K6R3CT"
			(at -36.186 300.176 0)
			(layer "F.Fab")
			(hide yes)
			(effects
				(font
					(size 1 1)
					(thickness 0.15)
				)
			)
		)
		(property "Manufacturer" "Walsin"
			(at -36.186 300.176 0)
			(layer "F.Fab")
			(hide yes)
			(effects
				(font
					(size 1 1)
					(thickness 0.15)
				)
			)
		)
		(property "Public" "False"
			(at -36.186 300.176 0)
			(layer "F.Fab")
			(hide yes)
			(effects
				(font
					(size 1 1)
					(thickness 0.15)
				)
			)
		)
		(property "Val" "100n"
			(at -36.186 300.176 0)
			(layer "F.Fab")
			(hide yes)
			(effects
				(font
					(size 1 1)
					(thickness 0.15)
				)
			)
		)
		(property "Voltage" ""
			(at -36.186 300.176 0)
			(layer "F.Fab")
			(hide yes)
			(effects
				(font
					(size 1 1)
					(thickness 0.15)
				)
			)
		)
		(sheetname "/PCIe-connector/")
		(sheetfile "pcie-conn.kicad_sch")
		(attr smd)
		(fp_rect
			(start -0.925 -0.47)
			(end 0.925 0.47)
			(stroke
				(width 0.05)
				(type default)
			)
			(fill no)
			(layer "F.CrtYd")
		)
		(fp_line
			(start -0.494 0.248)
			(end -0.494 -0.25)
			(stroke
				(width 0.15)
				(type solid)
			)
			(layer "F.Fab")
		)
		(fp_line
			(start 0.504 0.248)
			(end -0.494 0.248)
			(stroke
				(width 0.15)
				(type solid)
			)
			(layer "F.Fab")
		)
		(fp_line
			(start -0.494 -0.25)
			(end 0.504 -0.25)
			(stroke
				(width 0.15)
				(type solid)
			)
			(layer "F.Fab")
		)
		(fp_line
			(start 0.504 -0.25)
			(end 0.504 0.248)
			(stroke
				(width 0.15)
				(type solid)
			)
			(layer "F.Fab")
		)
		(pad "1" smd roundrect
			(at -0.48 0 270)
			(size 0.59 0.64)
			(layers "F.Cu" "F.Mask" "F.Paste")
			(roundrect_rratio 0.25)
			(net 374 "/PCIe-connector/PCIE_HPM_TX3_C_P")
			(pintype "passive")
		)
		(pad "2" smd roundrect
			(at 0.48 0 270)
			(size 0.59 0.64)
			(layers "F.Cu" "F.Mask" "F.Paste")
			(roundrect_rratio 0.25)
			(net 356 "PCIE_HPM_TX[3]_P")
			(pintype "passive")
		)
	)
	(footprint "antmicro-footprints:VQFN-20_1EP_4.5x2.5mm_P0.5mm"
		(layer "F.Cu")
		(at 78.015 166.115)
		(property "Reference" "U6"
			(at 1.285 -1.915 0)
			(layer "F.SilkS")
			(effects
				(font
					(size 0.7 0.7)
					(thickness 0.15)
				)
				(justify left bottom)
			)
		)
		(property "Value" "NVT2008BQ,115"
			(at 0.689 2.959 0)
			(layer "F.Fab")
			(effects
				(font
					(size 0.7 0.7)
					(thickness 0.15)
				)
				(justify left bottom)
			)
		)
		(property "Datasheet" "https://www.nxp.com/docs/en/data-sheet/NVT2008_NVT2010.pdf"
			(at 0 0 0)
			(layer "F.Fab")
			(hide yes)
			(effects
				(font
					(size 1.27 1.27)
					(thickness 0.15)
				)
			)
		)
		(property "Description" "Bidirectional Voltage Level Translator, 8 Inputs, 1.5ns, 1.8V to 5.5V, DHVQFN-20"
			(at 0 0 0)
			(layer "F.Fab")
			(hide yes)
			(effects
				(font
					(size 1.27 1.27)
					(thickness 0.15)
				)
			)
		)
		(property "Author" "Antmicro"
			(at 0 0 0)
			(layer "F.Fab")
			(hide yes)
			(effects
				(font
					(size 1 1)
					(thickness 0.15)
				)
			)
		)
		(property "License" "Apache-2.0"
			(at 0 0 0)
			(layer "F.Fab")
			(hide yes)
			(effects
				(font
					(size 1 1)
					(thickness 0.15)
				)
			)
		)
		(property "MPN" "NVT2008BQ,115"
			(at 0 0 0)
			(layer "F.Fab")
			(hide yes)
			(effects
				(font
					(size 1 1)
					(thickness 0.15)
				)
			)
		)
		(property "Manufacturer" "NXP"
			(at 0 0 0)
			(layer "F.Fab")
			(hide yes)
			(effects
				(font
					(size 1 1)
					(thickness 0.15)
				)
			)
		)
		(sheetname "/Interfaces/")
		(sheetfile "interfaces.kicad_sch")
		(attr smd)
		(fp_line
			(start -2.25 -1.25)
			(end -2.25 -0.5)
			(stroke
				(width 0.15)
				(type solid)
			)
			(layer "F.SilkS")
		)
		(fp_line
			(start -2.249 1.25)
			(end -2 1.25)
			(stroke
				(width 0.15)
				(type solid)
			)
			(layer "F.SilkS")
		)
		(fp_line
			(start -2.001 -1.25)
			(end -2.25 -1.25)
			(stroke
				(width 0.15)
				(type solid)
			)
			(layer "F.SilkS")
		)
		(fp_line
			(start 2.249 -1.25)
			(end 2 -1.25)
			(stroke
				(width 0.15)
				(type solid)
			)
			(layer "F.SilkS")
		)
		(fp_line
			(start 2.249 -1.25)
			(end 2.249 -0.5)
			(stroke
				(width 0.15)
				(type solid)
			)
			(layer "F.SilkS")
		)
		(fp_line
			(start 2.249 1.249)
			(end 2 1.249)
			(stroke
				(width 0.15)
				(type solid)
			)
			(layer "F.SilkS")
		)
		(fp_line
			(start 2.249 1.249)
			(end 2.249 0.5)
			(stroke
				(width 0.15)
				(type solid)
			)
			(layer "F.SilkS")
		)
		(fp_rect
			(start -2.711 -1.71)
			(end 2.708 1.709)
			(stroke
				(width 0.05)
				(type solid)
			)
			(fill no)
			(layer "F.CrtYd")
		)
		(fp_line
			(start -2.25 1.249)
			(end -2.25 -1.25)
			(stroke
				(width 0.15)
				(type solid)
			)
			(layer "F.Fab")
		)
		(fp_line
			(start 2.249 -1.25)
			(end -2.25 -1.25)
			(stroke
				(width 0.15)
				(type solid)
			)
			(layer "F.Fab")
		)
		(fp_line
			(start 2.249 1.249)
			(end -2.25 1.249)
			(stroke
				(width 0.15)
				(type solid)
			)
			(layer "F.Fab")
		)
		(fp_line
			(start 2.249 1.249)
			(end 2.249 -1.25)
			(stroke
				(width 0.15)
				(type solid)
			)
			(layer "F.Fab")
		)
		(pad "" smd roundrect
			(at -0.76 0)
			(size 1.31 0.95)
			(layers "F.Paste")
			(roundrect_rratio 0.05)
		)
		(pad "" smd roundrect
			(at 0.76 0)
			(size 1.31 0.95)
			(layers "F.Paste")
			(roundrect_rratio 0.05)
		)
		(pad "1" smd roundrect
			(at -2.15 0.25 90)
			(size 0.25 0.8)
			(layers "F.Cu" "F.Mask" "F.Paste")
			(roundrect_rratio 0.2)
			(net 1 "GND")
			(pinfunction "GND")
			(pintype "power_in")
		)
		(pad "2" smd roundrect
			(at -1.75 1.15)
			(size 0.25 0.8)
			(layers "F.Cu" "F.Mask" "F.Paste")
			(roundrect_rratio 0.2)
			(net 6 "VCC1V0")
			(pinfunction "VREFA")
			(pintype "power_in")
		)
		(pad "3" smd roundrect
			(at -1.25 1.15)
			(size 0.25 0.8)
			(layers "F.Cu" "F.Mask" "F.Paste")
			(roundrect_rratio 0.2)
			(net 49 "I3C[0]_SCL")
			(pinfunction "A1")
			(pintype "bidirectional")
		)
		(pad "4" smd roundrect
			(at -0.75 1.15)
			(size 0.25 0.8)
			(layers "F.Cu" "F.Mask" "F.Paste")
			(roundrect_rratio 0.2)
			(net 48 "I3C[0]_SDA")
			(pinfunction "A2")
			(pintype "bidirectional")
		)
		(pad "5" smd roundrect
			(at -0.25 1.15)
			(size 0.25 0.8)
			(layers "F.Cu" "F.Mask" "F.Paste")
			(roundrect_rratio 0.2)
			(net 52 "I3C[1]_SCL")
			(pinfunction "A3")
			(pintype "bidirectional")
		)
		(pad "6" smd roundrect
			(at 0.25 1.15)
			(size 0.25 0.8)
			(layers "F.Cu" "F.Mask" "F.Paste")
			(roundrect_rratio 0.2)
			(net 51 "I3C[1]_SDA")
			(pinfunction "A4")
			(pintype "bidirectional")
		)
		(pad "7" smd roundrect
			(at 0.75 1.15)
			(size 0.25 0.8)
			(layers "F.Cu" "F.Mask" "F.Paste")
			(roundrect_rratio 0.2)
			(net 47 "I3C[2]_SCL")
			(pinfunction "A5")
			(pintype "bidirectional")
		)
		(pad "8" smd roundrect
			(at 1.25 1.15)
			(size 0.25 0.8)
			(layers "F.Cu" "F.Mask" "F.Paste")
			(roundrect_rratio 0.2)
			(net 50 "I3C[2]_SDA")
			(pinfunction "A6")
			(pintype "bidirectional")
		)
		(pad "9" smd roundrect
			(at 1.75 1.15)
			(size 0.25 0.8)
			(layers "F.Cu" "F.Mask" "F.Paste")
			(roundrect_rratio 0.2)
			(net 54 "I3C[3]_SCL")
			(pinfunction "A7")
			(pintype "bidirectional")
		)
		(pad "10" smd roundrect
			(at 2.15 0.25 90)
			(size 0.25 0.8)
			(layers "F.Cu" "F.Mask" "F.Paste")
			(roundrect_rratio 0.2)
			(net 53 "I3C[3]_SDA")
			(pinfunction "A8")
			(pintype "bidirectional")
		)
		(pad "11" smd roundrect
			(at 2.15 -0.25 90)
			(size 0.25 0.8)
			(layers "F.Cu" "F.Mask" "F.Paste")
			(roundrect_rratio 0.2)
			(net 174 "I3C[3]_SDA_3V3")
			(pinfunction "B8")
			(pintype "bidirectional")
		)
		(pad "12" smd roundrect
			(at 1.75 -1.15)
			(size 0.25 0.8)
			(layers "F.Cu" "F.Mask" "F.Paste")
			(roundrect_rratio 0.2)
			(net 175 "I3C[3]_SCL_3V3")
			(pinfunction "B7")
			(pintype "bidirectional")
		)
		(pad "13" smd roundrect
			(at 1.25 -1.15)
			(size 0.25 0.8)
			(layers "F.Cu" "F.Mask" "F.Paste")
			(roundrect_rratio 0.2)
			(net 172 "I3C[2]_SDA_3V3")
			(pinfunction "B6")
			(pintype "bidirectional")
		)
		(pad "14" smd roundrect
			(at 0.75 -1.15)
			(size 0.25 0.8)
			(layers "F.Cu" "F.Mask" "F.Paste")
			(roundrect_rratio 0.2)
			(net 173 "I3C[2]_SCL_3V3")
			(pinfunction "B5")
			(pintype "bidirectional")
		)
		(pad "15" smd roundrect
			(at 0.25 -1.15)
			(size 0.25 0.8)
			(layers "F.Cu" "F.Mask" "F.Paste")
			(roundrect_rratio 0.2)
			(net 170 "I3C[1]_SDA_3V3")
			(pinfunction "B4")
			(pintype "bidirectional")
		)
		(pad "16" smd roundrect
			(at -0.25 -1.15)
			(size 0.25 0.8)
			(layers "F.Cu" "F.Mask" "F.Paste")
			(roundrect_rratio 0.2)
			(net 171 "I3C[1]_SCL_3V3")
			(pinfunction "B3")
			(pintype "bidirectional")
		)
		(pad "17" smd roundrect
			(at -0.75 -1.15)
			(size 0.25 0.8)
			(layers "F.Cu" "F.Mask" "F.Paste")
			(roundrect_rratio 0.2)
			(net 168 "I3C[0]_SDA_3V3")
			(pinfunction "B2")
			(pintype "bidirectional")
		)
		(pad "18" smd roundrect
			(at -1.25 -1.15)
			(size 0.25 0.8)
			(layers "F.Cu" "F.Mask" "F.Paste")
			(roundrect_rratio 0.2)
			(net 169 "I3C[0]_SCL_3V3")
			(pinfunction "B1")
			(pintype "bidirectional")
		)
		(pad "19" smd roundrect
			(at -1.75 -1.15)
			(size 0.25 0.8)
			(layers "F.Cu" "F.Mask" "F.Paste")
			(roundrect_rratio 0.2)
			(net 7 "/Interfaces/1V0_EN")
			(pinfunction "VREFB")
			(pintype "power_in")
		)
		(pad "20" smd roundrect
			(at -2.15 -0.25 90)
			(size 0.25 0.8)
			(layers "F.Cu" "F.Mask" "F.Paste")
			(roundrect_rratio 0.2)
			(net 7 "/Interfaces/1V0_EN")
			(pinfunction "EN")
			(pintype "input")
		)
		(pad "21" smd roundrect
			(at 0 0)
			(size 3 1)
			(layers "F.Cu" "F.Mask")
			(roundrect_rratio 0.05)
			(net 1 "GND")
			(pinfunction "EP")
			(pintype "power_in")
		)
	)
	(footprint "antmicro-footprints:R_0402_1005Metric"
		(layer "F.Cu")
		(at 77.2 67.7 -90)
		(descr "Resistor SMD 0402")
		(tags "resistor SMD 0402")
		(property "Reference" "R68"
			(at -0.9 16.03 90)
			(layer "F.SilkS")
			(effects
				(font
					(size 0.7 0.7)
					(thickness 0.15)
				)
				(justify right bottom)
			)
		)
		(property "Value" "R_100k_0402"
			(at 0 1.4 90)
			(layer "F.Fab")
			(effects
				(font
					(size 0.7 0.7)
					(thickness 0.15)
				)
				(justify right bottom)
			)
		)
		(property "Datasheet" "https://www.bourns.com/docs/product-datasheets/cr.pdf"
			(at 0 0 270)
			(layer "F.Fab")
			(hide yes)
			(effects
				(font
					(size 1.27 1.27)
					(thickness 0.15)
				)
			)
		)
		(property "Description" "SMD Chip Resistor, 100 kohm, ± 1%, 62.5 mW, 0402 [1005 Metric], Thick Film, General Purpose"
			(at 0 0 270)
			(layer "F.Fab")
			(hide yes)
			(effects
				(font
					(size 1.27 1.27)
					(thickness 0.15)
				)
			)
		)
		(property "Author" "Antmicro"
			(at 9.5 144.9 0)
			(layer "F.Fab")
			(hide yes)
			(effects
				(font
					(size 1 1)
					(thickness 0.15)
				)
			)
		)
		(property "License" "Apache-2.0"
			(at 9.5 144.9 0)
			(layer "F.Fab")
			(hide yes)
			(effects
				(font
					(size 1 1)
					(thickness 0.15)
				)
			)
		)
		(property "MPN" "CR0402-FX-1003GLF"
			(at 9.5 144.9 0)
			(layer "F.Fab")
			(hide yes)
			(effects
				(font
					(size 1 1)
					(thickness 0.15)
				)
			)
		)
		(property "Manufacturer" "Bourns"
			(at 9.5 144.9 0)
			(layer "F.Fab")
			(hide yes)
			(effects
				(font
					(size 1 1)
					(thickness 0.15)
				)
			)
		)
		(property "Tolerance" "1%"
			(at 9.5 144.9 0)
			(layer "F.Fab")
			(hide yes)
			(effects
				(font
					(size 1 1)
					(thickness 0.15)
				)
			)
		)
		(property "Val" "100k"
			(at 9.5 144.9 0)
			(layer "F.Fab")
			(hide yes)
			(effects
				(font
					(size 1 1)
					(thickness 0.15)
				)
			)
		)
		(sheetname "/Power supply/")
		(sheetfile "power-supply.kicad_sch")
		(attr smd)
		(fp_rect
			(start -0.925 -0.47)
			(end 0.925 0.47)
			(stroke
				(width 0.05)
				(type default)
			)
			(fill no)
			(layer "F.CrtYd")
		)
		(fp_rect
			(start -0.5 -0.25)
			(end 0.5 0.25)
			(stroke
				(width 0.15)
				(type solid)
			)
			(fill no)
			(layer "F.Fab")
		)
		(pad "1" smd roundrect
			(at -0.48 0 270)
			(size 0.59 0.64)
			(layers "F.Cu" "F.Mask" "F.Paste")
			(roundrect_rratio 0.25)
			(net 4 "VCC5V0")
			(pintype "passive")
		)
		(pad "2" smd roundrect
			(at 0.48 0 270)
			(size 0.59 0.64)
			(layers "F.Cu" "F.Mask" "F.Paste")
			(roundrect_rratio 0.25)
			(net 573 "/Power supply/5V0_PG")
			(pintype "passive")
		)
	)
)
